(kicad_pcb
	(version 20260206)
	(generator "pcbnew")
	(generator_version "10.0")
	(general
		(thickness 1.6)
		(legacy_teardrops no)
	)
	(paper "A4")
	(title_block
		(title "v1-tray-backplane — T6M_tray_BP_c_1023_1120.brd")
		(comment 1 "Open CloudServer (Microsoft) / footprints 63-63 of 170")
	)
	(layers
		(0 "F.Cu" signal "TOP")
		(4 "In1.Cu" signal "GND")
		(6 "In2.Cu" signal "IN1")
		(8 "In3.Cu" signal "VCC")
		(10 "In4.Cu" signal "VCC1")
		(12 "In5.Cu" signal "IN2")
		(14 "In6.Cu" signal "GND1")
		(2 "B.Cu" signal "BOTTOM")
		(9 "F.Adhes" user "F.Adhesive")
		(11 "B.Adhes" user "B.Adhesive")
		(13 "F.Paste" user "Package Geometry/Pastemask Top")
		(15 "B.Paste" user "Package Geometry/Pastemask Bottom")
		(5 "F.SilkS" user "Ref Des/Silkscreen Top")
		(7 "B.SilkS" user "Ref Des/Silkscreen Bottom")
		(1 "F.Mask" user "Board Geometry/Soldermask Top")
		(3 "B.Mask" user "Board Geometry/Soldermask Bottom")
		(17 "Dwgs.User" user "User.Drawings")
		(19 "Cmts.User" user "User.Comments")
		(21 "Eco1.User" user "User.Eco1")
		(23 "Eco2.User" user "User.Eco2")
		(25 "Edge.Cuts" user "Board Geometry/Outline")
		(27 "Margin" user)
		(31 "F.CrtYd" user "Package Geometry/Place Bound Top")
		(29 "B.CrtYd" user "Package Geometry/Place Bound Bottom")
		(35 "F.Fab" user "Ref Des/Assembly Top")
		(33 "B.Fab" user "Ref Des/Assembly Bottom")
	)
	(footprint ""
		(layer "F.Cu")
		(at 8.570214 -49.30013 180)
		(property "Reference" "J19"
			(at -19.65198 -7.666736 0)
			(unlocked yes)
			(layer "F.SilkS")
			(effects
				(font
					(size 0.7874 0.5842)
					(thickness 0.1524)
				)
				(justify left)
			)
		)
		(property "Value" ""
			(at 0 0 180)
			(layer "F.Fab")
			(effects
				(font
					(size 1.27 1.27)
				)
			)
		)
		(duplicate_pad_numbers_are_jumpers no)
		(fp_line
			(start 7.869936 2.500122)
			(end 6.370066 3.999992)
			(stroke
				(width 0.1524)
				(type default)
			)
			(layer "F.SilkS")
		)
		(fp_line
			(start 7.869936 -5.299964)
			(end 7.869936 2.500122)
			(stroke
				(width 0.1524)
				(type default)
			)
			(layer "F.SilkS")
		)
		(fp_line
			(start 6.370066 3.999992)
			(end -0.379984 3.999992)
			(stroke
				(width 0.1524)
				(type default)
			)
			(layer "F.SilkS")
		)
		(fp_line
			(start -0.379984 3.999992)
			(end -1.880108 2.500122)
			(stroke
				(width 0.1524)
				(type default)
			)
			(layer "F.SilkS")
		)
		(fp_line
			(start -1.764792 -6.850888)
			(end 7.869936 -6.850888)
			(stroke
				(width 0.1524)
				(type default)
			)
			(layer "F.SilkS")
		)
		(fp_line
			(start -1.880108 2.500122)
			(end -1.880108 -6.649974)
			(stroke
				(width 0.1524)
				(type default)
			)
			(layer "F.SilkS")
		)
		(fp_line
			(start -2.579878 -6.649974)
			(end -2.579878 -3.9624)
			(stroke
				(width 0.1524)
				(type default)
			)
			(layer "F.SilkS")
		)
		(fp_line
			(start -2.770378 2.690622)
			(end -4.080002 3.999992)
			(stroke
				(width 0.1524)
				(type default)
			)
			(layer "F.SilkS")
		)
		(fp_line
			(start -4.080002 3.999992)
			(end -42.7101 3.999992)
			(stroke
				(width 0.1524)
				(type default)
			)
			(layer "F.SilkS")
		)
		(fp_line
			(start -42.7101 3.999992)
			(end -44.20997 2.500122)
			(stroke
				(width 0.1524)
				(type default)
			)
			(layer "F.SilkS")
		)
		(fp_line
			(start -44.20997 2.500122)
			(end -44.20997 -5.299964)
			(stroke
				(width 0.1524)
				(type default)
			)
			(layer "F.SilkS")
		)
		(fp_line
			(start -44.20997 -6.850888)
			(end -2.704592 -6.850888)
			(stroke
				(width 0.1524)
				(type default)
			)
			(layer "F.SilkS")
		)
		(fp_arc
			(start -2.23012 -6.999986)
			(mid -1.98262 -6.897472)
			(end -1.880108 -6.649974)
			(stroke
				(width 0.1524)
				(type default)
			)
			(layer "F.SilkS")
		)
		(fp_arc
			(start -2.579878 -6.649974)
			(mid -2.477435 -6.897345)
			(end -2.23012 -6.999986)
			(stroke
				(width 0.1524)
				(type default)
			)
			(layer "F.SilkS")
		)
		(fp_line
			(start 7.869936 2.500122)
			(end 6.370066 3.999992)
			(stroke
				(width 0.1524)
				(type default)
			)
			(layer "B.SilkS")
		)
		(fp_line
			(start 7.869936 -5.299964)
			(end 7.869936 2.500122)
			(stroke
				(width 0.1524)
				(type default)
			)
			(layer "B.SilkS")
		)
		(fp_line
			(start 6.370066 3.999992)
			(end -0.379984 3.999992)
			(stroke
				(width 0.1524)
				(type default)
			)
			(layer "B.SilkS")
		)
		(fp_line
			(start -0.379984 3.999992)
			(end -1.880108 2.500122)
			(stroke
				(width 0.1524)
				(type default)
			)
			(layer "B.SilkS")
		)
		(fp_line
			(start -1.764792 -6.850888)
			(end 7.869936 -6.850888)
			(stroke
				(width 0.1524)
				(type default)
			)
			(layer "B.SilkS")
		)
		(fp_line
			(start -1.880108 2.500122)
			(end -1.880108 -6.649974)
			(stroke
				(width 0.1524)
				(type default)
			)
			(layer "B.SilkS")
		)
		(fp_line
			(start -2.579878 -6.649974)
			(end -2.579878 -4.0132)
			(stroke
				(width 0.1524)
				(type default)
			)
			(layer "B.SilkS")
		)
		(fp_line
			(start -2.770378 2.690622)
			(end -4.080002 3.999992)
			(stroke
				(width 0.1524)
				(type default)
			)
			(layer "B.SilkS")
		)
		(fp_line
			(start -4.080002 3.999992)
			(end -42.7101 3.999992)
			(stroke
				(width 0.1524)
				(type default)
			)
			(layer "B.SilkS")
		)
		(fp_line
			(start -42.7101 3.999992)
			(end -44.20997 2.500122)
			(stroke
				(width 0.1524)
				(type default)
			)
			(layer "B.SilkS")
		)
		(fp_line
			(start -44.20997 2.500122)
			(end -44.20997 -5.299964)
			(stroke
				(width 0.1524)
				(type default)
			)
			(layer "B.SilkS")
		)
		(fp_line
			(start -44.20997 -6.850888)
			(end -2.704592 -6.850888)
			(stroke
				(width 0.1524)
				(type default)
			)
			(layer "B.SilkS")
		)
		(fp_arc
			(start -2.23012 -6.999986)
			(mid -1.98262 -6.897472)
			(end -1.880108 -6.649974)
			(stroke
				(width 0.1524)
				(type default)
			)
			(layer "B.SilkS")
		)
		(fp_arc
			(start -2.579878 -6.649974)
			(mid -2.477435 -6.897345)
			(end -2.23012 -6.999986)
			(stroke
				(width 0.1524)
				(type default)
			)
			(layer "B.SilkS")
		)
		(fp_poly
			(pts
				(xy -44.204382 3.999992) (xy 7.865618 3.999992) (xy 7.865618 -6.850888) (xy -1.942592 -6.850888)
				(xy -1.942592 -7.0104) (xy -2.539492 -7.0104) (xy -2.539492 -6.850888) (xy -44.204382 -6.850888)
			)
			(stroke
				(width 0)
				(type default)
			)
			(fill no)
			(layer "B.CrtYd")
		)
		(fp_poly
			(pts
				(xy -44.204382 3.999992) (xy 7.865618 3.999992) (xy 7.865618 -6.850888) (xy -1.942592 -6.850888)
				(xy -1.942592 -7.0104) (xy -2.539492 -7.0104) (xy -2.539492 -6.850888) (xy -44.204382 -6.850888)
			)
			(stroke
				(width 0)
				(type default)
			)
			(fill no)
			(layer "F.CrtYd")
		)
		(fp_line
			(start 7.869936 2.500122)
			(end 6.370066 3.999992)
			(stroke
				(width 0.1)
				(type default)
			)
			(layer "B.Fab")
		)
		(fp_line
			(start 7.869936 -5.299964)
			(end 7.869936 2.500122)
			(stroke
				(width 0.1)
				(type default)
			)
			(layer "B.Fab")
		)
		(fp_line
			(start 6.370066 3.999992)
			(end -0.379984 3.999992)
			(stroke
				(width 0.1)
				(type default)
			)
			(layer "B.Fab")
		)
		(fp_line
			(start -0.379984 3.999992)
			(end -1.880108 2.500122)
			(stroke
				(width 0.1)
				(type default)
			)
			(layer "B.Fab")
		)
		(fp_line
			(start -1.764792 -6.850888)
			(end 7.869936 -6.850888)
			(stroke
				(width 0.1)
				(type default)
			)
			(layer "B.Fab")
		)
		(fp_line
			(start -1.880108 2.500122)
			(end -1.880108 -6.649974)
			(stroke
				(width 0.1)
				(type default)
			)
			(layer "B.Fab")
		)
		(fp_line
			(start -2.579878 2.500122)
			(end -4.080002 3.999992)
			(stroke
				(width 0.1)
				(type default)
			)
			(layer "B.Fab")
		)
		(fp_line
			(start -2.579878 -6.649974)
			(end -2.579878 2.500122)
			(stroke
				(width 0.1)
				(type default)
			)
			(layer "B.Fab")
		)
		(fp_line
			(start -4.080002 3.999992)
			(end -42.7101 3.999992)
			(stroke
				(width 0.1)
				(type default)
			)
			(layer "B.Fab")
		)
		(fp_line
			(start -42.7101 3.999992)
			(end -44.20997 2.500122)
			(stroke
				(width 0.1)
				(type default)
			)
			(layer "B.Fab")
		)
		(fp_line
			(start -44.20997 2.500122)
			(end -44.20997 -5.299964)
			(stroke
				(width 0.1)
				(type default)
			)
			(layer "B.Fab")
		)
		(fp_line
			(start -44.20997 -6.850888)
			(end -2.704592 -6.850888)
			(stroke
				(width 0.1)
				(type default)
			)
			(layer "B.Fab")
		)
		(fp_arc
			(start -2.23012 -6.999986)
			(mid -1.98262 -6.897472)
			(end -1.880108 -6.649974)
			(stroke
				(width 0.1)
				(type default)
			)
			(layer "B.Fab")
		)
		(fp_arc
			(start -2.579878 -6.649974)
			(mid -2.477435 -6.897345)
			(end -2.23012 -6.999986)
			(stroke
				(width 0.1)
				(type default)
			)
			(layer "B.Fab")
		)
		(fp_line
			(start 7.869936 2.500122)
			(end 6.370066 3.999992)
			(stroke
				(width 0.1)
				(type default)
			)
			(layer "F.Fab")
		)
		(fp_line
			(start 7.869936 -5.299964)
			(end 7.869936 2.500122)
			(stroke
				(width 0.1)
				(type default)
			)
			(layer "F.Fab")
		)
		(fp_line
			(start 6.370066 3.999992)
			(end -0.379984 3.999992)
			(stroke
				(width 0.1)
				(type default)
			)
			(layer "F.Fab")
		)
		(fp_line
			(start -0.379984 3.999992)
			(end -1.880108 2.500122)
			(stroke
				(width 0.1)
				(type default)
			)
			(layer "F.Fab")
		)
		(fp_line
			(start -1.764792 -6.850888)
			(end 7.869936 -6.850888)
			(stroke
				(width 0.1)
				(type default)
			)
			(layer "F.Fab")
		)
		(fp_line
			(start -1.880108 2.500122)
			(end -1.880108 -6.649974)
			(stroke
				(width 0.1)
				(type default)
			)
			(layer "F.Fab")
		)
		(fp_line
			(start -2.579878 2.500122)
			(end -4.080002 3.999992)
			(stroke
				(width 0.1)
				(type default)
			)
			(layer "F.Fab")
		)
		(fp_line
			(start -2.579878 -6.649974)
			(end -2.579878 2.500122)
			(stroke
				(width 0.1)
				(type default)
			)
			(layer "F.Fab")
		)
		(fp_line
			(start -4.080002 3.999992)
			(end -42.7101 3.999992)
			(stroke
				(width 0.1)
				(type default)
			)
			(layer "F.Fab")
		)
		(fp_line
			(start -42.7101 3.999992)
			(end -44.20997 2.500122)
			(stroke
				(width 0.1)
				(type default)
			)
			(layer "F.Fab")
		)
		(fp_line
			(start -44.20997 2.500122)
			(end -44.20997 -5.299964)
			(stroke
				(width 0.1)
				(type default)
			)
			(layer "F.Fab")
		)
		(fp_line
			(start -44.20997 -6.850888)
			(end -2.704592 -6.850888)
			(stroke
				(width 0.1)
				(type default)
			)
			(layer "F.Fab")
		)
		(fp_arc
			(start -2.23012 -6.999986)
			(mid -1.98262 -6.897472)
			(end -1.880108 -6.649974)
			(stroke
				(width 0.1)
				(type default)
			)
			(layer "F.Fab")
		)
		(fp_arc
			(start -2.579878 -6.649974)
			(mid -2.477435 -6.897345)
			(end -2.23012 -6.999986)
			(stroke
				(width 0.1)
				(type default)
			)
			(layer "F.Fab")
		)
		(fp_text user "S6"
			(at 7.735316 -7.92099 0)
			(unlocked yes)
			(layer "F.SilkS")
			(effects
				(font
					(size 0.7874 0.5842)
					(thickness 0.1524)
				)
				(justify left)
			)
		)
		(fp_text user "S1"
			(at 0.41021 -7.76859 0)
			(unlocked yes)
			(layer "F.SilkS")
			(effects
				(font
					(size 0.7874 0.5842)
					(thickness 0.1524)
				)
				(justify left)
			)
		)
		(fp_text user "P4"
			(at -5.83819 -8.415528 0)
			(unlocked yes)
			(layer "F.SilkS")
			(effects
				(font
					(size 0.7874 0.5842)
					(thickness 0.1524)
				)
				(justify left)
			)
		)
		(fp_text user "P1"
			(at -37.393372 -8.592312 0)
			(unlocked yes)
			(layer "F.SilkS")
			(effects
				(font
					(size 0.7874 0.5842)
					(thickness 0.1524)
				)
				(justify left)
			)
		)
		(fp_text user "S7"
			(at 6.56844 -7.71779 0)
			(unlocked yes)
			(layer "B.SilkS")
			(effects
				(font
					(size 0.7874 0.5842)
					(thickness 0.1524)
				)
				(justify left mirror)
			)
		)
		(fp_text user "S12"
			(at -1.53289 -7.66699 0)
			(unlocked yes)
			(layer "B.SilkS")
			(effects
				(font
					(size 0.7874 0.5842)
					(thickness 0.1524)
				)
				(justify left mirror)
			)
		)
		(fp_text user "P5"
			(at -7.20979 -8.161528 0)
			(unlocked yes)
			(layer "B.SilkS")
			(effects
				(font
					(size 0.7874 0.5842)
					(thickness 0.1524)
				)
				(justify left mirror)
			)
		)
		(fp_text user "P8"
			(at -39.552372 -8.566912 0)
			(unlocked yes)
			(layer "B.SilkS")
			(effects
				(font
					(size 0.7874 0.5842)
					(thickness 0.1524)
				)
				(justify left mirror)
			)
		)
		(fp_text user "S7"
			(at 6.939788 -6.09727 180)
			(unlocked yes)
			(layer "B.Fab")
			(effects
				(font
					(size 0.7874 0.5842)
					(thickness 0.000001)
				)
				(justify left mirror)
			)
		)
		(fp_text user "S12"
			(at 0.893318 -6.09727 180)
			(unlocked yes)
			(layer "B.Fab")
			(effects
				(font
					(size 0.7874 0.5842)
					(thickness 0.000001)
				)
				(justify left mirror)
			)
		)
		(fp_text user "P5"
			(at -6.586982 -6.059932 180)
			(unlocked yes)
			(layer "B.Fab")
			(effects
				(font
					(size 0.7874 0.5842)
					(thickness 0.000001)
				)
				(justify left mirror)
			)
		)
		(fp_text user "P8"
			(at -37.338 -6.010148 180)
			(unlocked yes)
			(layer "B.Fab")
			(effects
				(font
					(size 0.7874 0.5842)
					(thickness 0.000001)
				)
				(justify left mirror)
			)
		)
		(fp_text user "S6"
			(at 5.442712 -6.14807 180)
			(unlocked yes)
			(layer "F.Fab")
			(effects
				(font
					(size 0.7874 0.5842)
					(thickness 0.000001)
				)
				(justify left)
			)
		)
		(fp_text user "S1"
			(at -0.668782 -6.14807 180)
			(unlocked yes)
			(layer "F.Fab")
			(effects
				(font
					(size 0.7874 0.5842)
					(thickness 0.000001)
				)
				(justify left)
			)
		)
		(fp_text user "P4"
			(at -8.110982 -6.110732 180)
			(unlocked yes)
			(layer "F.Fab")
			(effects
				(font
					(size 0.7874 0.5842)
					(thickness 0.000001)
				)
				(justify left)
			)
		)
		(fp_text user "P1"
			(at -38.5318 -6.060948 180)
			(unlocked yes)
			(layer "F.Fab")
			(effects
				(font
					(size 0.7874 0.5842)
					(thickness 0.000001)
				)
				(justify left)
			)
		)
		(pad "P1" smd rect
			(at -37.79012 -0.649986 90)
			(size 6.2992 9.4742)
			(layers "F.Cu" "F.Mask" "F.Paste")
			(net "GND")
		)
		(pad "P2" smd rect
			(at -27.63012 -0.649986 90)
			(size 6.2992 9.4742)
			(layers "F.Cu" "F.Mask" "F.Paste")
			(net "GND")
		)
		(pad "P3" smd rect
			(at -17.47012 -0.649986 90)
			(size 6.2992 9.4742)
			(layers "F.Cu" "F.Mask" "F.Paste")
			(net "P12V")
		)
		(pad "P4" smd rect
			(at -7.31012 -0.649986 90)
			(size 6.2992 9.4742)
			(layers "F.Cu" "F.Mask" "F.Paste")
			(net "P12V")
		)
		(pad "P5" smd rect
			(at -7.31012 -0.649986 90)
			(size 6.2992 9.4742)
			(layers "F.Cu" "F.Mask" "F.Paste")
			(net "P12V")
		)
		(pad "P6" smd rect
			(at -17.47012 -0.649986 90)
			(size 6.2992 9.4742)
			(layers "F.Cu" "F.Mask" "F.Paste")
			(net "P12V")
		)
		(pad "P7" smd rect
			(at -27.63012 -0.649986 90)
			(size 6.2992 9.4742)
			(layers "F.Cu" "F.Mask" "F.Paste")
			(net "GND")
		)
		(pad "P8" smd rect
			(at -37.79012 -0.649986 90)
			(size 6.2992 9.4742)
			(layers "F.Cu" "F.Mask" "F.Paste")
			(net "GND")
		)
		(pad "S1" smd rect
			(at 0 0 180)
			(size 0.8128 5.0038)
			(layers "F.Cu" "F.Mask" "F.Paste")
			(net "NODE1_TXD")
		)
		(pad "S2" smd rect
			(at 1.27 0 180)
			(size 0.8128 5.0038)
			(layers "F.Cu" "F.Mask" "F.Paste")
			(net "NODE1_RXD")
		)
		(pad "S3" smd rect
			(at 2.54 0 180)
			(size 0.8128 5.0038)
			(layers "F.Cu" "F.Mask" "F.Paste")
			(net "NODE1_EN")
		)
		(pad "S4" smd rect
			(at 3.81 0 180)
			(size 0.8128 5.0038)
			(layers "F.Cu" "F.Mask" "F.Paste")
			(net "NODE2_EN")
		)
		(pad "S5" smd rect
			(at 5.08 0 180)
			(size 0.8128 5.0038)
			(layers "F.Cu" "F.Mask" "F.Paste")
			(net "NODE2_TXD")
		)
		(pad "S6" smd rect
			(at 6.35 0 180)
			(size 0.8128 5.0038)
			(layers "F.Cu" "F.Mask" "F.Paste")
			(net "NODE2_RXD")
		)
		(pad "S7" smd rect
			(at 6.35 0 180)
			(size 0.8128 5.0038)
			(layers "F.Cu" "F.Mask" "F.Paste")
			(net "NODE4_RXD")
		)
		(pad "S8" smd rect
			(at 5.08 0 180)
			(size 0.8128 5.0038)
			(layers "F.Cu" "F.Mask" "F.Paste")
			(net "NODE4_TXD")
		)
		(pad "S9" smd rect
			(at 3.81 0 180)
			(size 0.8128 5.0038)
			(layers "F.Cu" "F.Mask" "F.Paste")
			(net "NODE4_EN")
		)
		(pad "S10" smd rect
			(at 2.54 0 180)
			(size 0.8128 5.0038)
			(layers "F.Cu" "F.Mask" "F.Paste")
			(net "NODE3_EN")
		)
		(pad "S11" smd rect
			(at 1.27 0 180)
			(size 0.8128 5.0038)
			(layers "F.Cu" "F.Mask" "F.Paste")
			(net "NODE3_RXD")
		)
		(pad "S12" smd rect
			(at 0 0 180)
			(size 0.8128 5.0038)
			(layers "F.Cu" "F.Mask" "F.Paste")
			(net "NODE3_TXD")
		)
		(zone
			(layers "F.Cu" "B.Cu" "In1.Cu" "In2.Cu" "In3.Cu" "In4.Cu" "In5.Cu" "In6.Cu")
			(hatch none 0.5)
			(connect_pads
				(clearance 0)
			)
			(min_thickness 0.25)
			(keepout
				(tracks allowed)
				(vias not_allowed)
				(pads allowed)
				(copperpour not_allowed)
				(footprints allowed)
			)
			(placement
				(enabled no)
				(sheetname "")
			)
			(fill
				(thermal_gap 0.5)
				(thermal_bridge_width 0.5)
				(island_removal_mode 0)
			)
			(polygon
				(pts
					(xy 9.049004 -45.467524) (xy 9.049004 -51.868324) (xy 1.759204 -51.868324) (xy 1.759204 -45.467524)
				)
			)
		)
		(zone
			(layers "F.Cu" "B.Cu" "In1.Cu" "In2.Cu" "In3.Cu" "In4.Cu" "In5.Cu" "In6.Cu")
			(hatch none 0.5)
			(connect_pads
				(clearance 0)
			)
			(min_thickness 0.25)
			(keepout
				(tracks allowed)
				(vias not_allowed)
				(pads allowed)
				(copperpour not_allowed)
				(footprints allowed)
			)
			(placement
				(enabled no)
				(sheetname "")
			)
			(fill
				(thermal_gap 0.5)
				(thermal_bridge_width 0.5)
				(island_removal_mode 0)
			)
			(polygon
				(pts
					(xy 51.166014 -51.86553) (xy 11.084814 -51.86553) (xy 11.084814 -44.169838) (xy 51.166014 -44.169838)
				)
			)
		)
		(zone
			(layers "F.Cu" "B.Cu" "In1.Cu" "In2.Cu" "In3.Cu" "In4.Cu" "In5.Cu" "In6.Cu")
			(hatch none 0.5)
			(connect_pads
				(clearance 0)
			)
			(min_thickness 0.25)
			(keepout
				(tracks not_allowed)
				(vias allowed)
				(pads allowed)
				(copperpour not_allowed)
				(footprints allowed)
			)
			(placement
				(enabled no)
				(sheetname "")
			)
			(fill
				(thermal_gap 0.5)
				(thermal_bridge_width 0.5)
				(island_removal_mode 0)
			)
			(polygon
				(pts
					(xy 51.269392 -53.300122) (xy 52.780184 -51.78933) (xy 52.780184 -45.449744) (xy 51.162966 -45.449744)
					(xy 51.162966 -51.86553) (xy 41.551606 -51.86553) (xy 41.551606 -45.449744) (xy 41.002966 -45.449744)
					(xy 41.002966 -51.86553) (xy 31.391606 -51.86553) (xy 31.391606 -45.449744) (xy 30.842966 -45.449744)
					(xy 30.842966 -51.863244) (xy 21.429726 -51.863244) (xy 21.427186 -51.86553) (xy 21.231606 -51.86553)
					(xy 21.231606 -45.449744) (xy 20.685506 -45.449744) (xy 20.685506 -51.863244) (xy 11.269726 -51.863244)
					(xy 11.269726 -51.86553) (xy 11.200892 -51.86553) (xy 12.635738 -53.300122)
				)
			)
		)
		(zone
			(layers "F.Cu" "B.Cu" "In1.Cu" "In2.Cu" "In3.Cu" "In4.Cu" "In5.Cu" "In6.Cu")
			(hatch none 0.5)
			(connect_pads
				(clearance 0)
			)
			(min_thickness 0.25)
			(keepout
				(tracks not_allowed)
				(vias allowed)
				(pads allowed)
				(copperpour not_allowed)
				(footprints allowed)
			)
			(placement
				(enabled no)
				(sheetname "")
			)
			(fill
				(thermal_gap 0.5)
				(thermal_bridge_width 0.5)
				(island_removal_mode 0)
			)
			(polygon
				(pts
					(xy 8.93953 -53.300122) (xy 10.450322 -51.78933) (xy 10.450322 -46.74743) (xy 9.040114 -46.74743)
					(xy 9.040114 -51.86553) (xy 8.100314 -51.86553) (xy 8.100314 -46.74743) (xy 7.770114 -46.74743)
					(xy 7.770114 -51.86553) (xy 6.830314 -51.86553) (xy 6.830314 -46.74743) (xy 6.500114 -46.74743)
					(xy 6.500114 -51.86553) (xy 5.560314 -51.86553) (xy 5.560314 -46.74743) (xy 5.230114 -46.74743)
					(xy 5.230114 -51.86553) (xy 4.290314 -51.86553) (xy 4.290314 -46.74743) (xy 3.960114 -46.74743)
					(xy 3.960114 -51.86553) (xy 3.020314 -51.86553) (xy 3.020314 -46.74743) (xy 2.690114 -46.74743)
					(xy 2.690114 -51.86553) (xy 1.750314 -51.86553) (xy 1.750314 -46.74743) (xy 0.700278 -46.74743)
					(xy 0.700278 -51.78933) (xy 2.21107 -53.300122)
				)
			)
		)
	)
)
